(kicad_pcb
	(version 20241229)
	(generator "pcbnew")
	(generator_version "9.0")
	(general
		(thickness 1.62)
		(legacy_teardrops no)
	)
	(paper "A3")
	(title_block
		(title "COM Express 7 Baseboard")
		(date "2025-02-04")
		(rev "1.1.2")
		(company "Antmicro Ltd")
		(comment 1 "www.antmicro.com")
		(comment 9 "footprints 416-420 of 802")
	)
	(layers
		(0 "F.Cu" signal)
		(4 "In1.Cu" signal)
		(6 "In2.Cu" signal)
		(8 "In3.Cu" signal)
		(10 "In4.Cu" signal)
		(12 "In5.Cu" signal)
		(14 "In6.Cu" signal)
		(2 "B.Cu" signal)
		(9 "F.Adhes" user "F.Adhesive")
		(11 "B.Adhes" user "B.Adhesive")
		(13 "F.Paste" user)
		(15 "B.Paste" user)
		(5 "F.SilkS" user "F.Silkscreen")
		(7 "B.SilkS" user "B.Silkscreen")
		(1 "F.Mask" user)
		(3 "B.Mask" user)
		(17 "Dwgs.User" user "User.Drawings")
		(19 "Cmts.User" user "User.Comments")
		(21 "Eco1.User" user "User.Eco1")
		(23 "Eco2.User" user "User.Eco2")
		(25 "Edge.Cuts" user)
		(27 "Margin" user)
		(31 "F.CrtYd" user "F.Courtyard")
		(29 "B.CrtYd" user "B.Courtyard")
		(35 "F.Fab" user)
		(33 "B.Fab" user)
	)
	(footprint "antmicro-footprints:R_0402_1005Metric"
		(layer "F.Cu")
		(at 112.9 148.86 180)
		(descr "Resistor SMD 0402")
		(tags "resistor SMD 0402")
		(property "Reference" "R202"
			(at 0.85 -0.45 0)
			(layer "F.SilkS")
			(effects
				(font
					(size 0.7 0.7)
					(thickness 0.15)
				)
				(justify right bottom)
			)
		)
		(property "Value" "R_1k_0402"
			(at -1.011843 1.772047 0)
			(layer "F.Fab")
			(effects
				(font
					(size 0.7 0.7)
					(thickness 0.15)
				)
				(justify right bottom)
			)
		)
		(property "Datasheet" "https://www.bourns.com/docs/product-datasheets/cr.pdf"
			(at 0 0 180)
			(layer "F.Fab")
			(hide yes)
			(effects
				(font
					(size 1.27 1.27)
					(thickness 0.15)
				)
			)
		)
		(property "Author" "Antmicro"
			(at 225.8 297.72 0)
			(layer "F.Fab")
			(hide yes)
			(effects
				(font
					(size 1 1)
					(thickness 0.15)
				)
			)
		)
		(property "License" "Apache-2.0"
			(at 225.8 297.72 0)
			(layer "F.Fab")
			(hide yes)
			(effects
				(font
					(size 1 1)
					(thickness 0.15)
				)
			)
		)
		(property "MPN" "CR0402-FX-1001GLF"
			(at 225.8 297.72 0)
			(layer "F.Fab")
			(hide yes)
			(effects
				(font
					(size 1 1)
					(thickness 0.15)
				)
			)
		)
		(property "Manufacturer" "Bourns"
			(at 225.8 297.72 0)
			(layer "F.Fab")
			(hide yes)
			(effects
				(font
					(size 1 1)
					(thickness 0.15)
				)
			)
		)
		(property "Public" "False"
			(at 225.8 297.72 0)
			(layer "F.Fab")
			(hide yes)
			(effects
				(font
					(size 1 1)
					(thickness 0.15)
				)
			)
		)
		(property "Tolerance" "1%"
			(at 225.8 297.72 0)
			(layer "F.Fab")
			(hide yes)
			(effects
				(font
					(size 1 1)
					(thickness 0.15)
				)
			)
		)
		(property "Val" "1k"
			(at 225.8 297.72 0)
			(layer "F.Fab")
			(hide yes)
			(effects
				(font
					(size 1 1)
					(thickness 0.15)
				)
			)
		)
		(sheetname "PCIe redriver")
		(sheetfile "pcie_redriver.kicad_sch")
		(attr smd)
		(fp_rect
			(start -0.925 -0.47)
			(end 0.925 0.47)
			(stroke
				(width 0.05)
				(type default)
			)
			(fill no)
			(layer "F.CrtYd")
		)
		(fp_rect
			(start -0.5 -0.25)
			(end 0.5 0.25)
			(stroke
				(width 0.15)
				(type solid)
			)
			(fill no)
			(layer "F.Fab")
		)
		(pad "1" smd roundrect
			(at -0.48 0 180)
			(size 0.59 0.64)
			(layers "F.Cu" "F.Mask" "F.Paste")
			(roundrect_rratio 0.25)
			(net 2 "+3V3")
			(pintype "passive")
			(teardrops
				(best_length_ratio 0.2)
				(max_length 1)
				(best_width_ratio 0.9)
				(max_width 2)
				(curved_edges yes)
				(filter_ratio 0.9)
				(enabled yes)
				(allow_two_segments yes)
				(prefer_zone_connections yes)
			)
		)
		(pad "2" smd roundrect
			(at 0.48 0 180)
			(size 0.59 0.64)
			(layers "F.Cu" "F.Mask" "F.Paste")
			(roundrect_rratio 0.25)
			(net 623 "/PCIe redriver/TX_EQ0")
			(pintype "passive")
			(teardrops
				(best_length_ratio 0.2)
				(max_length 1)
				(best_width_ratio 0.9)
				(max_width 2)
				(curved_edges yes)
				(filter_ratio 0.9)
				(enabled yes)
				(allow_two_segments yes)
				(prefer_zone_connections yes)
			)
		)
	)
	(footprint "antmicro-footprints:R_0201"
		(layer "F.Cu")
		(at 137.412 147.935 -90)
		(descr "Resistor SMD 0201")
		(tags "resistor SMD 0201")
		(property "Reference" "R285"
			(at 6.475 -0.288 270)
			(layer "F.SilkS")
			(effects
				(font
					(size 0.7 0.7)
					(thickness 0.15)
				)
				(justify left bottom)
			)
		)
		(property "Value" "R_0R_0201"
			(at 0 1.25 270)
			(layer "F.Fab")
			(effects
				(font
					(size 0.7 0.7)
					(thickness 0.15)
				)
				(justify left bottom)
			)
		)
		(property "Datasheet" "https://www.bourns.com/docs/product-datasheets/cr.pdf"
			(at 0 0 270)
			(layer "F.Fab")
			(hide yes)
			(effects
				(font
					(size 1.27 1.27)
					(thickness 0.15)
				)
			)
		)
		(property "Author" "Antmicro"
			(at -10.523 285.347 0)
			(layer "F.Fab")
			(hide yes)
			(effects
				(font
					(size 1 1)
					(thickness 0.15)
				)
			)
		)
		(property "License" "Apache-2.0"
			(at -10.523 285.347 0)
			(layer "F.Fab")
			(hide yes)
			(effects
				(font
					(size 1 1)
					(thickness 0.15)
				)
			)
		)
		(property "MPN" "CR0201-FX-0R00GLF"
			(at -10.523 285.347 0)
			(layer "F.Fab")
			(hide yes)
			(effects
				(font
					(size 1 1)
					(thickness 0.15)
				)
			)
		)
		(property "Manufacturer" "Bourns"
			(at -10.523 285.347 0)
			(layer "F.Fab")
			(hide yes)
			(effects
				(font
					(size 1 1)
					(thickness 0.15)
				)
			)
		)
		(property "Tolerance" "1%"
			(at -10.523 285.347 0)
			(layer "F.Fab")
			(hide yes)
			(effects
				(font
					(size 1 1)
					(thickness 0.15)
				)
			)
		)
		(property "Val" "0R"
			(at -10.523 285.347 0)
			(layer "F.Fab")
			(hide yes)
			(effects
				(font
					(size 1 1)
					(thickness 0.15)
				)
			)
		)
		(sheetname "KR to SFI #2")
		(sheetfile "kr_sfi.kicad_sch")
		(attr smd dnp)
		(fp_rect
			(start -0.7 -0.35)
			(end 0.7 0.35)
			(stroke
				(width 0.05)
				(type default)
			)
			(fill no)
			(layer "F.CrtYd")
		)
		(fp_rect
			(start -0.3 -0.15)
			(end 0.298 0.148)
			(stroke
				(width 0.15)
				(type solid)
			)
			(fill no)
			(layer "F.Fab")
		)
		(pad "" smd roundrect
			(at -0.346 0 270)
			(size 0.318 0.36)
			(layers "F.Paste")
			(roundrect_rratio 0.25)
			(teardrops
				(best_length_ratio 0.2)
				(max_length 1)
				(best_width_ratio 0.9)
				(max_width 2)
				(curved_edges yes)
				(filter_ratio 0.9)
				(enabled yes)
				(allow_two_segments yes)
				(prefer_zone_connections yes)
			)
		)
		(pad "" smd roundrect
			(at 0.344 0 270)
			(size 0.318 0.36)
			(layers "F.Paste")
			(roundrect_rratio 0.25)
			(teardrops
				(best_length_ratio 0.2)
				(max_length 1)
				(best_width_ratio 0.9)
				(max_width 2)
				(curved_edges yes)
				(filter_ratio 0.9)
				(enabled yes)
				(allow_two_segments yes)
				(prefer_zone_connections yes)
			)
		)
		(pad "1" smd roundrect
			(at -0.32 0 270)
			(size 0.46 0.4)
			(layers "F.Cu" "F.Mask")
			(roundrect_rratio 0.25)
			(net 119 "/2xSFP+/10GKR_SFP1.TX+")
			(pintype "passive")
			(teardrops
				(best_length_ratio 0.2)
				(max_length 1)
				(best_width_ratio 0.9)
				(max_width 2)
				(curved_edges yes)
				(filter_ratio 0.9)
				(enabled yes)
				(allow_two_segments yes)
				(prefer_zone_connections yes)
			)
		)
		(pad "2" smd roundrect
			(at 0.32 0 270)
			(size 0.46 0.4)
			(layers "F.Cu" "F.Mask")
			(roundrect_rratio 0.25)
			(net 955 "/2xSFP+/KR to SFI #2/BYP_TX+")
			(pintype "passive")
			(teardrops
				(best_length_ratio 0.2)
				(max_length 1)
				(best_width_ratio 0.9)
				(max_width 2)
				(curved_edges yes)
				(filter_ratio 0.9)
				(enabled yes)
				(allow_two_segments yes)
				(prefer_zone_connections yes)
			)
		)
	)
	(footprint "antmicro-footprints:C_Pol_EIA-B"
		(layer "F.Cu")
		(at 308.825 116.435)
		(property "Reference" "C51"
			(at 2.275 0.475 0)
			(layer "F.SilkS")
			(effects
				(font
					(size 0.7 0.7)
					(thickness 0.15)
				)
				(justify left bottom)
			)
		)
		(property "Value" "C_Pol_100u_10V_KEMET-T520-B"
			(at 0 2.85 0)
			(layer "F.Fab")
			(effects
				(font
					(size 0.7 0.7)
					(thickness 0.15)
				)
				(justify left bottom)
			)
		)
		(property "Datasheet" "https://www.kemet.com/en/us/capacitors/product/T520B107M010ATE070.html"
			(at 0 0 0)
			(layer "F.Fab")
			(hide yes)
			(effects
				(font
					(size 1.27 1.27)
					(thickness 0.15)
				)
			)
		)
		(property "Author" "Antmicro"
			(at 0 0 0)
			(layer "F.Fab")
			(hide yes)
			(effects
				(font
					(size 1 1)
					(thickness 0.15)
				)
			)
		)
		(property "Dielectric" "template_dielectric"
			(at 0 0 0)
			(layer "F.Fab")
			(hide yes)
			(effects
				(font
					(size 1 1)
					(thickness 0.15)
				)
			)
		)
		(property "License" "Apache-2.0"
			(at 0 0 0)
			(layer "F.Fab")
			(hide yes)
			(effects
				(font
					(size 1 1)
					(thickness 0.15)
				)
			)
		)
		(property "MPN" "T520B107M010ATE070"
			(at 0 0 0)
			(layer "F.Fab")
			(hide yes)
			(effects
				(font
					(size 1 1)
					(thickness 0.15)
				)
			)
		)
		(property "Manufacturer" "KEMET"
			(at 0 0 0)
			(layer "F.Fab")
			(hide yes)
			(effects
				(font
					(size 1 1)
					(thickness 0.15)
				)
			)
		)
		(property "Public" "False"
			(at 0 0 0)
			(layer "F.Fab")
			(hide yes)
			(effects
				(font
					(size 1 1)
					(thickness 0.15)
				)
			)
		)
		(property "Val" "100u"
			(at 0 0 0)
			(layer "F.Fab")
			(hide yes)
			(effects
				(font
					(size 1 1)
					(thickness 0.15)
				)
			)
		)
		(property "Voltage" "10V"
			(at 0 0 0)
			(layer "F.Fab")
			(hide yes)
			(effects
				(font
					(size 1 1)
					(thickness 0.15)
				)
			)
		)
		(sheetname "Power")
		(sheetfile "power.kicad_sch")
		(attr smd)
		(fp_line
			(start -2.521 -1.676)
			(end -2.123 -1.676)
			(stroke
				(width 0.15)
				(type solid)
			)
			(layer "F.SilkS")
		)
		(fp_line
			(start -2.325 -1.475)
			(end -2.325 -1.878)
			(stroke
				(width 0.15)
				(type solid)
			)
			(layer "F.SilkS")
		)
		(fp_line
			(start -1.8 -1.6)
			(end 1.8 -1.6)
			(stroke
				(width 0.15)
				(type solid)
			)
			(layer "F.SilkS")
		)
		(fp_line
			(start -1.8 -1.3)
			(end -1.8 -1.6)
			(stroke
				(width 0.15)
				(type solid)
			)
			(layer "F.SilkS")
		)
		(fp_line
			(start -1.8 1.3)
			(end -1.8 1.6)
			(stroke
				(width 0.15)
				(type solid)
			)
			(layer "F.SilkS")
		)
		(fp_line
			(start 1.8 -1.3)
			(end 1.8 -1.6)
			(stroke
				(width 0.15)
				(type solid)
			)
			(layer "F.SilkS")
		)
		(fp_line
			(start 1.8 1.3)
			(end 1.8 1.6)
			(stroke
				(width 0.15)
				(type solid)
			)
			(layer "F.SilkS")
		)
		(fp_line
			(start 1.8 1.6)
			(end -1.8 1.6)
			(stroke
				(width 0.15)
				(type solid)
			)
			(layer "F.SilkS")
		)
		(fp_line
			(start -2.411 -1.35)
			(end -2.41 1.35)
			(stroke
				(width 0.05)
				(type solid)
			)
			(layer "F.CrtYd")
		)
		(fp_line
			(start -1.97 -1.75)
			(end -1.97 -1.35)
			(stroke
				(width 0.05)
				(type solid)
			)
			(layer "F.CrtYd")
		)
		(fp_line
			(start -1.97 -1.35)
			(end -2.41 -1.35)
			(stroke
				(width 0.05)
				(type solid)
			)
			(layer "F.CrtYd")
		)
		(fp_line
			(start -1.97 1.35)
			(end -2.41 1.35)
			(stroke
				(width 0.05)
				(type solid)
			)
			(layer "F.CrtYd")
		)
		(fp_line
			(start -1.97 1.35)
			(end -1.97 1.75)
			(stroke
				(width 0.05)
				(type solid)
			)
			(layer "F.CrtYd")
		)
		(fp_line
			(start 1.959 -1.75)
			(end -1.97 -1.75)
			(stroke
				(width 0.05)
				(type solid)
			)
			(layer "F.CrtYd")
		)
		(fp_line
			(start 1.959 -1.75)
			(end 1.959 -1.35)
			(stroke
				(width 0.05)
				(type solid)
			)
			(layer "F.CrtYd")
		)
		(fp_line
			(start 1.96 1.35)
			(end 1.96 1.75)
			(stroke
				(width 0.05)
				(type solid)
			)
			(layer "F.CrtYd")
		)
		(fp_line
			(start 1.96 1.75)
			(end -1.97 1.75)
			(stroke
				(width 0.05)
				(type solid)
			)
			(layer "F.CrtYd")
		)
		(fp_line
			(start 2.399 -1.35)
			(end 1.959 -1.35)
			(stroke
				(width 0.05)
				(type solid)
			)
			(layer "F.CrtYd")
		)
		(fp_line
			(start 2.399 -1.35)
			(end 2.4 1.35)
			(stroke
				(width 0.05)
				(type solid)
			)
			(layer "F.CrtYd")
		)
		(fp_line
			(start 2.4 1.35)
			(end 1.96 1.35)
			(stroke
				(width 0.05)
				(type solid)
			)
			(layer "F.CrtYd")
		)
		(fp_line
			(start -1.7 1.324)
			(end -1.551 1.475)
			(stroke
				(width 0.15)
				(type solid)
			)
			(layer "F.Fab")
		)
		(fp_rect
			(start -1.72 -1.5)
			(end 1.719 1.499)
			(stroke
				(width 0.15)
				(type solid)
			)
			(fill no)
			(layer "F.Fab")
		)
		(pad "1" smd roundrect
			(at -1.551 0)
			(size 1.2 2.2)
			(layers "F.Cu" "F.Mask" "F.Paste")
			(roundrect_rratio 0.1)
			(net 70 "Net-(C49-Pad2)")
			(pintype "passive")
			(teardrops
				(best_length_ratio 0.2)
				(max_length 1)
				(best_width_ratio 0.9)
				(max_width 2)
				(curved_edges yes)
				(filter_ratio 0.9)
				(enabled yes)
				(allow_two_segments yes)
				(prefer_zone_connections yes)
			)
		)
		(pad "2" smd roundrect
			(at 1.55 0)
			(size 1.2 2.2)
			(layers "F.Cu" "F.Mask" "F.Paste")
			(roundrect_rratio 0.1)
			(net 1 "GND")
			(pintype "passive")
			(teardrops
				(best_length_ratio 0.2)
				(max_length 1)
				(best_width_ratio 0.9)
				(max_width 2)
				(curved_edges yes)
				(filter_ratio 0.9)
				(enabled yes)
				(allow_two_segments yes)
				(prefer_zone_connections yes)
			)
		)
	)
	(footprint "antmicro-footprints:TP_SMD_0.75mm"
		(layer "F.Cu")
		(at 199.70861 72.802163 -90)
		(property "Reference" "TP99"
			(at 0 -0.6 90)
			(layer "F.SilkS")
			(hide yes)
			(effects
				(font
					(size 0.7 0.7)
					(thickness 0.15)
				)
				(justify right bottom)
			)
		)
		(property "Value" "TP_0.75mm_SMD"
			(at 0 1.2 90)
			(layer "F.Fab")
			(effects
				(font
					(size 0.7 0.7)
					(thickness 0.15)
				)
				(justify right bottom)
			)
		)
		(property "Author" "Antmicro"
			(at 126.906447 272.510773 0)
			(layer "F.Fab")
			(hide yes)
			(effects
				(font
					(size 1 1)
					(thickness 0.15)
				)
			)
		)
		(property "License" "Apache-2.0"
			(at 126.906447 272.510773 0)
			(layer "F.Fab")
			(hide yes)
			(effects
				(font
					(size 1 1)
					(thickness 0.15)
				)
			)
		)
		(property "MPN" ""
			(at 126.906447 272.510773 0)
			(layer "F.Fab")
			(hide yes)
			(effects
				(font
					(size 1 1)
					(thickness 0.15)
				)
			)
		)
		(property "Manufacturer" ""
			(at 126.906447 272.510773 0)
			(layer "F.Fab")
			(hide yes)
			(effects
				(font
					(size 1 1)
					(thickness 0.15)
				)
			)
		)
		(property "Public" "False"
			(at 126.906447 272.510773 0)
			(layer "F.Fab")
			(hide yes)
			(effects
				(font
					(size 1 1)
					(thickness 0.15)
				)
			)
		)
		(sheetname "Power")
		(sheetfile "power.kicad_sch")
		(attr exclude_from_pos_files exclude_from_bom)
		(fp_circle
			(center 0 0)
			(end 0.475 0)
			(stroke
				(width 0.05)
				(type default)
			)
			(fill no)
			(layer "F.CrtYd")
		)
		(pad "1" smd circle
			(at 0 0 270)
			(size 0.75 0.75)
			(layers "F.Cu" "F.Mask")
			(net 78 "+1V8")
			(pinfunction "1")
			(pintype "passive")
			(teardrops
				(best_length_ratio 0.4)
				(max_length 1)
				(best_width_ratio 0.9)
				(max_width 2)
				(curved_edges yes)
				(filter_ratio 0.9)
				(enabled yes)
				(allow_two_segments yes)
				(prefer_zone_connections yes)
			)
		)
	)
	(footprint "antmicro-footprints:C_0603_1608Metric"
		(layer "F.Cu")
		(at 315.6005 95.1365 90)
		(descr "Capacitor SMD 0603")
		(tags "capacitor 0603")
		(property "Reference" "C58"
			(at 1.1765 0.4495 90)
			(layer "F.SilkS")
			(effects
				(font
					(size 0.7 0.7)
					(thickness 0.15)
				)
				(justify left bottom)
			)
		)
		(property "Value" "C_22u_16V_0603"
			(at -1.42757 1.770288 90)
			(layer "F.Fab")
			(effects
				(font
					(size 0.7 0.7)
					(thickness 0.15)
				)
				(justify left bottom)
			)
		)
		(property "Datasheet" "https://product.samsungsem.com/mlcc/CL10A226MO7JZN.do"
			(at 0 0 90)
			(layer "F.Fab")
			(hide yes)
			(effects
				(font
					(size 1.27 1.27)
					(thickness 0.15)
				)
			)
		)
		(property "Author" "Antmicro"
			(at 410.737 -220.464 0)
			(layer "F.Fab")
			(hide yes)
			(effects
				(font
					(size 1 1)
					(thickness 0.15)
				)
			)
		)
		(property "Dielectric" ""
			(at 410.737 -220.464 0)
			(layer "F.Fab")
			(hide yes)
			(effects
				(font
					(size 1 1)
					(thickness 0.15)
				)
			)
		)
		(property "License" "Apache-2.0"
			(at 410.737 -220.464 0)
			(layer "F.Fab")
			(hide yes)
			(effects
				(font
					(size 1 1)
					(thickness 0.15)
				)
			)
		)
		(property "MPN" "CL10A226MO7JZNC"
			(at 410.737 -220.464 0)
			(layer "F.Fab")
			(hide yes)
			(effects
				(font
					(size 1 1)
					(thickness 0.15)
				)
			)
		)
		(property "Manufacturer" "Samsung Electro-Mechanics"
			(at 410.737 -220.464 0)
			(layer "F.Fab")
			(hide yes)
			(effects
				(font
					(size 1 1)
					(thickness 0.15)
				)
			)
		)
		(property "Public" "False"
			(at 410.737 -220.464 0)
			(layer "F.Fab")
			(hide yes)
			(effects
				(font
					(size 1 1)
					(thickness 0.15)
				)
			)
		)
		(property "Val" "22u"
			(at 410.737 -220.464 0)
			(layer "F.Fab")
			(hide yes)
			(effects
				(font
					(size 1 1)
					(thickness 0.15)
				)
			)
		)
		(property "Voltage" "16V"
			(at 410.737 -220.464 0)
			(layer "F.Fab")
			(hide yes)
			(effects
				(font
					(size 1 1)
					(thickness 0.15)
				)
			)
		)
		(sheetname "Power")
		(sheetfile "power.kicad_sch")
		(attr smd)
		(fp_line
			(start -0.15 -0.4)
			(end 0.15 -0.4)
			(stroke
				(width 0.15)
				(type solid)
			)
			(layer "F.SilkS")
		)
		(fp_line
			(start -0.15 0.4)
			(end 0.15 0.4)
			(stroke
				(width 0.15)
				(type solid)
			)
			(layer "F.SilkS")
		)
		(fp_rect
			(start -1.25 -0.65)
			(end 1.25 0.65)
			(stroke
				(width 0.05)
				(type solid)
			)
			(fill no)
			(layer "F.CrtYd")
		)
		(fp_rect
			(start -0.8 -0.4)
			(end 0.8 0.4)
			(stroke
				(width 0.15)
				(type solid)
			)
			(fill no)
			(layer "F.Fab")
		)
		(pad "1" smd roundrect
			(at -0.7 0 90)
			(size 0.8 1)
			(layers "F.Cu" "F.Mask" "F.Paste")
			(roundrect_rratio 0.2)
			(net 1 "GND")
			(pintype "passive")
			(teardrops
				(best_length_ratio 0.2)
				(max_length 1)
				(best_width_ratio 0.9)
				(max_width 2)
				(curved_edges yes)
				(filter_ratio 0.9)
				(enabled yes)
				(allow_two_segments yes)
				(prefer_zone_connections yes)
			)
		)
		(pad "2" smd roundrect
			(at 0.7 0 90)
			(size 0.8 1)
			(layers "F.Cu" "F.Mask" "F.Paste")
			(roundrect_rratio 0.2)
			(net 62 "+12V_AON")
			(pintype "passive")
			(teardrops
				(best_length_ratio 0.2)
				(max_length 1)
				(best_width_ratio 0.9)
				(max_width 2)
				(curved_edges yes)
				(filter_ratio 0.9)
				(enabled yes)
				(allow_two_segments yes)
				(prefer_zone_connections yes)
			)
		)
	)
)
